(kicad_pcb
	(version 20260206)
	(generator "pcbnew")
	(generator_version "10.0")
	(general
		(thickness 1.6)
		(legacy_teardrops no)
	)
	(paper "A4")
	(title_block
		(title "03242023_DA0F0TMBIJ0_F0T_Motherboard_J_brd_V01_OCP.brd")
		(comment 1 "Grand Teton / footprints 200-206 of 6105")
	)
	(layers
		(0 "F.Cu" signal "TOP")
		(4 "In1.Cu" signal "GND")
		(6 "In2.Cu" signal "IN1")
		(8 "In3.Cu" signal "GND1")
		(10 "In4.Cu" signal "IN2")
		(12 "In5.Cu" signal "GND2")
		(14 "In6.Cu" signal "IN3")
		(16 "In7.Cu" signal "GND3")
		(18 "In8.Cu" signal "VCC")
		(20 "In9.Cu" signal "VCC1")
		(22 "In10.Cu" signal "GND4")
		(24 "In11.Cu" signal "IN4")
		(26 "In12.Cu" signal "GND5")
		(28 "In13.Cu" signal "IN5")
		(30 "In14.Cu" signal "GND6")
		(32 "In15.Cu" signal "IN6")
		(34 "In16.Cu" signal "GND7")
		(2 "B.Cu" signal "BOTTOM")
		(9 "F.Adhes" user "F.Adhesive")
		(11 "B.Adhes" user "B.Adhesive")
		(13 "F.Paste" user "Package Geometry/Pastemask Top")
		(15 "B.Paste" user "Package Geometry/Pastemask Bottom")
		(5 "F.SilkS" user "Ref Des/Silkscreen Top")
		(7 "B.SilkS" user "Ref Des/Silkscreen Bottom")
		(1 "F.Mask" user "Board Geometry/Soldermask Top")
		(3 "B.Mask" user "Board Geometry/Soldermask Bottom")
		(17 "Dwgs.User" user "User.Drawings")
		(19 "Cmts.User" user "User.Comments")
		(21 "Eco1.User" user "User.Eco1")
		(23 "Eco2.User" user "User.Eco2")
		(25 "Edge.Cuts" user "Board Geometry/Outline")
		(27 "Margin" user)
		(31 "F.CrtYd" user "Package Geometry/Place Bound Top")
		(29 "B.CrtYd" user "Package Geometry/Place Bound Bottom")
		(35 "F.Fab" user "Ref Des/Assembly Top")
		(33 "B.Fab" user "Ref Des/Assembly Bottom")
	)
	(footprint ""
		(layer "F.Cu")
		(at 106.32313 -241.97691 -90)
		(property "Reference" "C280"
			(at 0 0 270)
			(layer "F.SilkS")
			(hide yes)
			(effects
				(font
					(size 1.27 1.27)
				)
			)
		)
		(property "Value" ""
			(at 0 0 270)
			(layer "F.Fab")
			(effects
				(font
					(size 1.27 1.27)
				)
			)
		)
		(duplicate_pad_numbers_are_jumpers no)
		(fp_line
			(start -0.7874 0.4064)
			(end -0.7874 -0.4064)
			(stroke
				(width 0.1524)
				(type default)
			)
			(layer "F.SilkS")
		)
		(fp_line
			(start 0.7874 0.4064)
			(end -0.7874 0.4064)
			(stroke
				(width 0.1524)
				(type default)
			)
			(layer "F.SilkS")
		)
		(fp_line
			(start -0.7874 -0.4064)
			(end 0.7874 -0.4064)
			(stroke
				(width 0.1524)
				(type default)
			)
			(layer "F.SilkS")
		)
		(fp_line
			(start 0.7874 -0.4064)
			(end 0.7874 0.4064)
			(stroke
				(width 0.1524)
				(type default)
			)
			(layer "F.SilkS")
		)
		(fp_line
			(start -0.67945 0.3048)
			(end -0.67945 -0.305054)
			(stroke
				(width 0.1)
				(type default)
			)
			(layer "F.Fab")
		)
		(fp_line
			(start -0.12065 0.3048)
			(end -0.67945 0.3048)
			(stroke
				(width 0.1)
				(type default)
			)
			(layer "F.Fab")
		)
		(fp_line
			(start 0.120396 0.3048)
			(end 0.120396 0.2794)
			(stroke
				(width 0.1)
				(type default)
			)
			(layer "F.Fab")
		)
		(fp_line
			(start 0.67945 0.3048)
			(end 0.120396 0.3048)
			(stroke
				(width 0.1)
				(type default)
			)
			(layer "F.Fab")
		)
		(fp_line
			(start -0.12065 0.2794)
			(end -0.12065 0.3048)
			(stroke
				(width 0.1)
				(type default)
			)
			(layer "F.Fab")
		)
		(fp_line
			(start 0.120396 0.2794)
			(end -0.12065 0.2794)
			(stroke
				(width 0.1)
				(type default)
			)
			(layer "F.Fab")
		)
		(fp_line
			(start -0.12065 -0.2794)
			(end 0.12065 -0.2794)
			(stroke
				(width 0.1)
				(type default)
			)
			(layer "F.Fab")
		)
		(fp_line
			(start 0.12065 -0.2794)
			(end 0.12065 -0.3048)
			(stroke
				(width 0.1)
				(type default)
			)
			(layer "F.Fab")
		)
		(fp_line
			(start 0.12065 -0.3048)
			(end 0.67945 -0.3048)
			(stroke
				(width 0.1)
				(type default)
			)
			(layer "F.Fab")
		)
		(fp_line
			(start 0.67945 -0.3048)
			(end 0.67945 0.3048)
			(stroke
				(width 0.1)
				(type default)
			)
			(layer "F.Fab")
		)
		(fp_line
			(start -0.67945 -0.305054)
			(end -0.12065 -0.305054)
			(stroke
				(width 0.1)
				(type default)
			)
			(layer "F.Fab")
		)
		(fp_line
			(start -0.12065 -0.305054)
			(end -0.12065 -0.2794)
			(stroke
				(width 0.1)
				(type default)
			)
			(layer "F.Fab")
		)
		(pad "1" smd circle
			(at -0.40005 0 270)
			(size 0 0)
			(layers "F.Cu" "F.Mask" "F.Paste")
			(net "PVCCIN_CPU1")
		)
		(pad "2" smd circle
			(at 0.40005 0 270)
			(size 0 0)
			(layers "F.Cu" "F.Mask" "F.Paste")
			(net "GND")
		)
	)
	(footprint ""
		(layer "F.Cu")
		(at 84.713318 -402.371052 -90)
		(property "Reference" "C734"
			(at 0 0 270)
			(layer "F.SilkS")
			(hide yes)
			(effects
				(font
					(size 1.27 1.27)
				)
			)
		)
		(property "Value" ""
			(at 0 0 270)
			(layer "F.Fab")
			(effects
				(font
					(size 1.27 1.27)
				)
			)
		)
		(duplicate_pad_numbers_are_jumpers no)
		(fp_line
			(start -0.299974 0.150114)
			(end -0.299974 -0.150114)
			(stroke
				(width 0.1)
				(type default)
			)
			(layer "F.Fab")
		)
		(fp_line
			(start 0.299974 0.150114)
			(end -0.299974 0.150114)
			(stroke
				(width 0.1)
				(type default)
			)
			(layer "F.Fab")
		)
		(fp_line
			(start -0.299974 -0.150114)
			(end 0.299974 -0.150114)
			(stroke
				(width 0.1)
				(type default)
			)
			(layer "F.Fab")
		)
		(fp_line
			(start 0.299974 -0.150114)
			(end 0.299974 0.150114)
			(stroke
				(width 0.1)
				(type default)
			)
			(layer "F.Fab")
		)
		(pad "1" smd rect
			(at -0.2667 0 270)
			(size 0.3048 0.381)
			(layers "F.Cu" "F.Mask" "F.Paste")
			(net "P5E_CPU1_PE0_TX_C_DN<3>")
		)
		(pad "2" smd rect
			(at 0.2667 0 270)
			(size 0.3048 0.381)
			(layers "F.Cu" "F.Mask" "F.Paste")
			(net "P5E_CPU1_PE0_TX_DN<3>")
		)
	)
	(footprint ""
		(layer "F.Cu")
		(at 187.892182 -28.258008 180)
		(property "Reference" "PC2233"
			(at 0 0 180)
			(layer "F.SilkS")
			(hide yes)
			(effects
				(font
					(size 1.27 1.27)
				)
			)
		)
		(property "Value" ""
			(at 0 0 180)
			(layer "F.Fab")
			(effects
				(font
					(size 1.27 1.27)
				)
			)
		)
		(duplicate_pad_numbers_are_jumpers no)
		(fp_line
			(start 0.7874 0.4064)
			(end -0.7874 0.4064)
			(stroke
				(width 0.1524)
				(type default)
			)
			(layer "F.SilkS")
		)
		(fp_line
			(start 0.7874 -0.4064)
			(end 0.7874 0.4064)
			(stroke
				(width 0.1524)
				(type default)
			)
			(layer "F.SilkS")
		)
		(fp_line
			(start -0.7874 0.4064)
			(end -0.7874 -0.4064)
			(stroke
				(width 0.1524)
				(type default)
			)
			(layer "F.SilkS")
		)
		(fp_line
			(start -0.7874 -0.4064)
			(end 0.7874 -0.4064)
			(stroke
				(width 0.1524)
				(type default)
			)
			(layer "F.SilkS")
		)
		(fp_line
			(start 0.67945 0.3048)
			(end 0.120396 0.3048)
			(stroke
				(width 0.1)
				(type default)
			)
			(layer "F.Fab")
		)
		(fp_line
			(start 0.67945 -0.3048)
			(end 0.67945 0.3048)
			(stroke
				(width 0.1)
				(type default)
			)
			(layer "F.Fab")
		)
		(fp_line
			(start 0.12065 -0.2794)
			(end 0.12065 -0.3048)
			(stroke
				(width 0.1)
				(type default)
			)
			(layer "F.Fab")
		)
		(fp_line
			(start 0.12065 -0.3048)
			(end 0.67945 -0.3048)
			(stroke
				(width 0.1)
				(type default)
			)
			(layer "F.Fab")
		)
		(fp_line
			(start 0.120396 0.3048)
			(end 0.120396 0.2794)
			(stroke
				(width 0.1)
				(type default)
			)
			(layer "F.Fab")
		)
		(fp_line
			(start 0.120396 0.2794)
			(end -0.12065 0.2794)
			(stroke
				(width 0.1)
				(type default)
			)
			(layer "F.Fab")
		)
		(fp_line
			(start -0.12065 0.3048)
			(end -0.67945 0.3048)
			(stroke
				(width 0.1)
				(type default)
			)
			(layer "F.Fab")
		)
		(fp_line
			(start -0.12065 0.2794)
			(end -0.12065 0.3048)
			(stroke
				(width 0.1)
				(type default)
			)
			(layer "F.Fab")
		)
		(fp_line
			(start -0.12065 -0.2794)
			(end 0.12065 -0.2794)
			(stroke
				(width 0.1)
				(type default)
			)
			(layer "F.Fab")
		)
		(fp_line
			(start -0.12065 -0.305054)
			(end -0.12065 -0.2794)
			(stroke
				(width 0.1)
				(type default)
			)
			(layer "F.Fab")
		)
		(fp_line
			(start -0.67945 0.3048)
			(end -0.67945 -0.305054)
			(stroke
				(width 0.1)
				(type default)
			)
			(layer "F.Fab")
		)
		(fp_line
			(start -0.67945 -0.305054)
			(end -0.12065 -0.305054)
			(stroke
				(width 0.1)
				(type default)
			)
			(layer "F.Fab")
		)
		(pad "1" smd circle
			(at -0.40005 0 180)
			(size 0 0)
			(layers "F.Cu" "F.Mask" "F.Paste")
			(net "P12V_SCM_VCC")
		)
		(pad "2" smd circle
			(at 0.40005 0 180)
			(size 0 0)
			(layers "F.Cu" "F.Mask" "F.Paste")
			(net "GND")
		)
	)
	(footprint ""
		(layer "F.Cu")
		(at 354.262944 -241.976656 -90)
		(property "Reference" "C1019"
			(at 0 0 270)
			(layer "F.SilkS")
			(hide yes)
			(effects
				(font
					(size 1.27 1.27)
				)
			)
		)
		(property "Value" ""
			(at 0 0 270)
			(layer "F.Fab")
			(effects
				(font
					(size 1.27 1.27)
				)
			)
		)
		(duplicate_pad_numbers_are_jumpers no)
		(fp_line
			(start -0.7874 0.4064)
			(end -0.7874 -0.4064)
			(stroke
				(width 0.1524)
				(type default)
			)
			(layer "F.SilkS")
		)
		(fp_line
			(start 0.7874 0.4064)
			(end -0.7874 0.4064)
			(stroke
				(width 0.1524)
				(type default)
			)
			(layer "F.SilkS")
		)
		(fp_line
			(start -0.7874 -0.4064)
			(end 0.7874 -0.4064)
			(stroke
				(width 0.1524)
				(type default)
			)
			(layer "F.SilkS")
		)
		(fp_line
			(start 0.7874 -0.4064)
			(end 0.7874 0.4064)
			(stroke
				(width 0.1524)
				(type default)
			)
			(layer "F.SilkS")
		)
		(fp_line
			(start -0.67945 0.3048)
			(end -0.67945 -0.305054)
			(stroke
				(width 0.1)
				(type default)
			)
			(layer "F.Fab")
		)
		(fp_line
			(start -0.12065 0.3048)
			(end -0.67945 0.3048)
			(stroke
				(width 0.1)
				(type default)
			)
			(layer "F.Fab")
		)
		(fp_line
			(start 0.120396 0.3048)
			(end 0.120396 0.2794)
			(stroke
				(width 0.1)
				(type default)
			)
			(layer "F.Fab")
		)
		(fp_line
			(start 0.67945 0.3048)
			(end 0.120396 0.3048)
			(stroke
				(width 0.1)
				(type default)
			)
			(layer "F.Fab")
		)
		(fp_line
			(start -0.12065 0.2794)
			(end -0.12065 0.3048)
			(stroke
				(width 0.1)
				(type default)
			)
			(layer "F.Fab")
		)
		(fp_line
			(start 0.120396 0.2794)
			(end -0.12065 0.2794)
			(stroke
				(width 0.1)
				(type default)
			)
			(layer "F.Fab")
		)
		(fp_line
			(start -0.12065 -0.2794)
			(end 0.12065 -0.2794)
			(stroke
				(width 0.1)
				(type default)
			)
			(layer "F.Fab")
		)
		(fp_line
			(start 0.12065 -0.2794)
			(end 0.12065 -0.3048)
			(stroke
				(width 0.1)
				(type default)
			)
			(layer "F.Fab")
		)
		(fp_line
			(start 0.12065 -0.3048)
			(end 0.67945 -0.3048)
			(stroke
				(width 0.1)
				(type default)
			)
			(layer "F.Fab")
		)
		(fp_line
			(start 0.67945 -0.3048)
			(end 0.67945 0.3048)
			(stroke
				(width 0.1)
				(type default)
			)
			(layer "F.Fab")
		)
		(fp_line
			(start -0.67945 -0.305054)
			(end -0.12065 -0.305054)
			(stroke
				(width 0.1)
				(type default)
			)
			(layer "F.Fab")
		)
		(fp_line
			(start -0.12065 -0.305054)
			(end -0.12065 -0.2794)
			(stroke
				(width 0.1)
				(type default)
			)
			(layer "F.Fab")
		)
		(pad "1" smd circle
			(at -0.40005 0 270)
			(size 0 0)
			(layers "F.Cu" "F.Mask" "F.Paste")
			(net "PVCCIN_CPU0")
		)
		(pad "2" smd circle
			(at 0.40005 0 270)
			(size 0 0)
			(layers "F.Cu" "F.Mask" "F.Paste")
			(net "GND")
		)
	)
	(footprint ""
		(layer "F.Cu")
		(at 263.101582 -67.08902)
		(property "Reference" "PR1326"
			(at 0 0 0)
			(layer "F.SilkS")
			(hide yes)
			(effects
				(font
					(size 1.27 1.27)
				)
			)
		)
		(property "Value" ""
			(at 0 0 0)
			(layer "F.Fab")
			(effects
				(font
					(size 1.27 1.27)
				)
			)
		)
		(duplicate_pad_numbers_are_jumpers no)
		(fp_line
			(start -0.7874 -0.4064)
			(end 0.7874 -0.4064)
			(stroke
				(width 0.1524)
				(type default)
			)
			(layer "F.SilkS")
		)
		(fp_line
			(start -0.7874 0.4064)
			(end -0.7874 -0.4064)
			(stroke
				(width 0.1524)
				(type default)
			)
			(layer "F.SilkS")
		)
		(fp_line
			(start 0.7874 -0.4064)
			(end 0.7874 0.4064)
			(stroke
				(width 0.1524)
				(type default)
			)
			(layer "F.SilkS")
		)
		(fp_line
			(start 0.7874 0.4064)
			(end -0.7874 0.4064)
			(stroke
				(width 0.1524)
				(type default)
			)
			(layer "F.SilkS")
		)
		(fp_line
			(start -0.67945 -0.305054)
			(end -0.12065 -0.305054)
			(stroke
				(width 0.1)
				(type default)
			)
			(layer "F.Fab")
		)
		(fp_line
			(start -0.67945 0.3048)
			(end -0.67945 -0.305054)
			(stroke
				(width 0.1)
				(type default)
			)
			(layer "F.Fab")
		)
		(fp_line
			(start -0.12065 -0.305054)
			(end -0.12065 -0.2794)
			(stroke
				(width 0.1)
				(type default)
			)
			(layer "F.Fab")
		)
		(fp_line
			(start -0.12065 -0.2794)
			(end 0.12065 -0.2794)
			(stroke
				(width 0.1)
				(type default)
			)
			(layer "F.Fab")
		)
		(fp_line
			(start -0.12065 0.2794)
			(end -0.12065 0.3048)
			(stroke
				(width 0.1)
				(type default)
			)
			(layer "F.Fab")
		)
		(fp_line
			(start -0.12065 0.3048)
			(end -0.67945 0.3048)
			(stroke
				(width 0.1)
				(type default)
			)
			(layer "F.Fab")
		)
		(fp_line
			(start 0.120396 0.2794)
			(end -0.12065 0.2794)
			(stroke
				(width 0.1)
				(type default)
			)
			(layer "F.Fab")
		)
		(fp_line
			(start 0.120396 0.3048)
			(end 0.120396 0.2794)
			(stroke
				(width 0.1)
				(type default)
			)
			(layer "F.Fab")
		)
		(fp_line
			(start 0.12065 -0.3048)
			(end 0.67945 -0.3048)
			(stroke
				(width 0.1)
				(type default)
			)
			(layer "F.Fab")
		)
		(fp_line
			(start 0.12065 -0.2794)
			(end 0.12065 -0.3048)
			(stroke
				(width 0.1)
				(type default)
			)
			(layer "F.Fab")
		)
		(fp_line
			(start 0.67945 -0.3048)
			(end 0.67945 0.3048)
			(stroke
				(width 0.1)
				(type default)
			)
			(layer "F.Fab")
		)
		(fp_line
			(start 0.67945 0.3048)
			(end 0.120396 0.3048)
			(stroke
				(width 0.1)
				(type default)
			)
			(layer "F.Fab")
		)
		(pad "1" smd circle
			(at -0.40005 0)
			(size 0 0)
			(layers "F.Cu" "F.Mask" "F.Paste")
			(net "P3V3_AUX")
		)
		(pad "2" smd circle
			(at 0.40005 0)
			(size 0 0)
			(layers "F.Cu" "F.Mask" "F.Paste")
			(net "P1V05_PCH_AUX_VCC")
		)
	)
	(footprint ""
		(layer "F.Cu")
		(at 117.36832 -337.955382)
		(property "Reference" "PC528_P1_3"
			(at 0 0 0)
			(layer "F.SilkS")
			(hide yes)
			(effects
				(font
					(size 1.27 1.27)
				)
			)
		)
		(property "Value" ""
			(at 0 0 0)
			(layer "F.Fab")
			(effects
				(font
					(size 1.27 1.27)
				)
			)
		)
		(duplicate_pad_numbers_are_jumpers no)
		(fp_line
			(start -0.7874 -0.4064)
			(end 0.7874 -0.4064)
			(stroke
				(width 0.1524)
				(type default)
			)
			(layer "F.SilkS")
		)
		(fp_line
			(start -0.7874 0.4064)
			(end -0.7874 -0.4064)
			(stroke
				(width 0.1524)
				(type default)
			)
			(layer "F.SilkS")
		)
		(fp_line
			(start 0.7874 -0.4064)
			(end 0.7874 0.4064)
			(stroke
				(width 0.1524)
				(type default)
			)
			(layer "F.SilkS")
		)
		(fp_line
			(start 0.7874 0.4064)
			(end -0.7874 0.4064)
			(stroke
				(width 0.1524)
				(type default)
			)
			(layer "F.SilkS")
		)
		(fp_line
			(start -0.67945 -0.305054)
			(end -0.12065 -0.305054)
			(stroke
				(width 0.1)
				(type default)
			)
			(layer "F.Fab")
		)
		(fp_line
			(start -0.67945 0.3048)
			(end -0.67945 -0.305054)
			(stroke
				(width 0.1)
				(type default)
			)
			(layer "F.Fab")
		)
		(fp_line
			(start -0.12065 -0.305054)
			(end -0.12065 -0.2794)
			(stroke
				(width 0.1)
				(type default)
			)
			(layer "F.Fab")
		)
		(fp_line
			(start -0.12065 -0.2794)
			(end 0.12065 -0.2794)
			(stroke
				(width 0.1)
				(type default)
			)
			(layer "F.Fab")
		)
		(fp_line
			(start -0.12065 0.2794)
			(end -0.12065 0.3048)
			(stroke
				(width 0.1)
				(type default)
			)
			(layer "F.Fab")
		)
		(fp_line
			(start -0.12065 0.3048)
			(end -0.67945 0.3048)
			(stroke
				(width 0.1)
				(type default)
			)
			(layer "F.Fab")
		)
		(fp_line
			(start 0.120396 0.2794)
			(end -0.12065 0.2794)
			(stroke
				(width 0.1)
				(type default)
			)
			(layer "F.Fab")
		)
		(fp_line
			(start 0.120396 0.3048)
			(end 0.120396 0.2794)
			(stroke
				(width 0.1)
				(type default)
			)
			(layer "F.Fab")
		)
		(fp_line
			(start 0.12065 -0.3048)
			(end 0.67945 -0.3048)
			(stroke
				(width 0.1)
				(type default)
			)
			(layer "F.Fab")
		)
		(fp_line
			(start 0.12065 -0.2794)
			(end 0.12065 -0.3048)
			(stroke
				(width 0.1)
				(type default)
			)
			(layer "F.Fab")
		)
		(fp_line
			(start 0.67945 -0.3048)
			(end 0.67945 0.3048)
			(stroke
				(width 0.1)
				(type default)
			)
			(layer "F.Fab")
		)
		(fp_line
			(start 0.67945 0.3048)
			(end 0.120396 0.3048)
			(stroke
				(width 0.1)
				(type default)
			)
			(layer "F.Fab")
		)
		(pad "1" smd circle
			(at -0.40005 0)
			(size 0 0)
			(layers "F.Cu" "F.Mask" "F.Paste")
			(net "SW_P12V_PVCCIN_CPU1_FLT")
		)
		(pad "2" smd circle
			(at 0.40005 0)
			(size 0 0)
			(layers "F.Cu" "F.Mask" "F.Paste")
			(net "GND")
		)
	)
	(footprint ""
		(layer "F.Cu")
		(at 309.522622 -35.804348)
		(property "Reference" "R1546"
			(at 0 0 0)
			(layer "F.SilkS")
			(hide yes)
			(effects
				(font
					(size 1.27 1.27)
				)
			)
		)
		(property "Value" ""
			(at 0 0 0)
			(layer "F.Fab")
			(effects
				(font
					(size 1.27 1.27)
				)
			)
		)
		(duplicate_pad_numbers_are_jumpers no)
		(fp_line
			(start -0.7874 -0.4064)
			(end 0.7874 -0.4064)
			(stroke
				(width 0.1524)
				(type default)
			)
			(layer "F.SilkS")
		)
		(fp_line
			(start -0.7874 0.4064)
			(end -0.7874 -0.4064)
			(stroke
				(width 0.1524)
				(type default)
			)
			(layer "F.SilkS")
		)
		(fp_line
			(start 0.7874 -0.4064)
			(end 0.7874 0.4064)
			(stroke
				(width 0.1524)
				(type default)
			)
			(layer "F.SilkS")
		)
		(fp_line
			(start 0.7874 0.4064)
			(end -0.7874 0.4064)
			(stroke
				(width 0.1524)
				(type default)
			)
			(layer "F.SilkS")
		)
		(fp_line
			(start -0.67945 -0.305054)
			(end -0.12065 -0.305054)
			(stroke
				(width 0.1)
				(type default)
			)
			(layer "F.Fab")
		)
		(fp_line
			(start -0.67945 0.3048)
			(end -0.67945 -0.305054)
			(stroke
				(width 0.1)
				(type default)
			)
			(layer "F.Fab")
		)
		(fp_line
			(start -0.12065 -0.305054)
			(end -0.12065 -0.2794)
			(stroke
				(width 0.1)
				(type default)
			)
			(layer "F.Fab")
		)
		(fp_line
			(start -0.12065 -0.2794)
			(end 0.12065 -0.2794)
			(stroke
				(width 0.1)
				(type default)
			)
			(layer "F.Fab")
		)
		(fp_line
			(start -0.12065 0.2794)
			(end -0.12065 0.3048)
			(stroke
				(width 0.1)
				(type default)
			)
			(layer "F.Fab")
		)
		(fp_line
			(start -0.12065 0.3048)
			(end -0.67945 0.3048)
			(stroke
				(width 0.1)
				(type default)
			)
			(layer "F.Fab")
		)
		(fp_line
			(start 0.120396 0.2794)
			(end -0.12065 0.2794)
			(stroke
				(width 0.1)
				(type default)
			)
			(layer "F.Fab")
		)
		(fp_line
			(start 0.120396 0.3048)
			(end 0.120396 0.2794)
			(stroke
				(width 0.1)
				(type default)
			)
			(layer "F.Fab")
		)
		(fp_line
			(start 0.12065 -0.3048)
			(end 0.67945 -0.3048)
			(stroke
				(width 0.1)
				(type default)
			)
			(layer "F.Fab")
		)
		(fp_line
			(start 0.12065 -0.2794)
			(end 0.12065 -0.3048)
			(stroke
				(width 0.1)
				(type default)
			)
			(layer "F.Fab")
		)
		(fp_line
			(start 0.67945 -0.3048)
			(end 0.67945 0.3048)
			(stroke
				(width 0.1)
				(type default)
			)
			(layer "F.Fab")
		)
		(fp_line
			(start 0.67945 0.3048)
			(end 0.120396 0.3048)
			(stroke
				(width 0.1)
				(type default)
			)
			(layer "F.Fab")
		)
		(pad "1" smd circle
			(at -0.40005 0)
			(size 0 0)
			(layers "F.Cu" "F.Mask" "F.Paste")
			(net "SMB_SML0B_3V3AUX_SDA")
		)
		(pad "2" smd circle
			(at 0.40005 0)
			(size 0 0)
			(layers "F.Cu" "F.Mask" "F.Paste")
			(net "P3V3_AUX")
		)
	)
)
